(kicad_pcb
	(version 20260206)
	(generator "pcbnew")
	(generator_version "10.0")
	(general
		(thickness 1.6)
		(legacy_teardrops no)
	)
	(paper "A4")
	(title_block
		(title "01162023_DA0F0TEBIF0_F0T_Expander_BD_F_brd_V02_OCP.brd")
		(comment 1 "Grand Teton / footprints 8381-8387 of 9728")
	)
	(layers
		(0 "F.Cu" signal "TOP")
		(4 "In1.Cu" signal "GND")
		(6 "In2.Cu" signal "VCC")
		(8 "In3.Cu" signal "VCC1")
		(10 "In4.Cu" signal "GND1")
		(12 "In5.Cu" signal "IN1")
		(14 "In6.Cu" signal "GND2")
		(16 "In7.Cu" signal "IN2")
		(18 "In8.Cu" signal "GND3")
		(20 "In9.Cu" signal "IN3")
		(22 "In10.Cu" signal "GND4")
		(24 "In11.Cu" signal "IN4")
		(26 "In12.Cu" signal "GND5")
		(28 "In13.Cu" signal "IN5")
		(30 "In14.Cu" signal "GND6")
		(32 "In15.Cu" signal "IN6")
		(34 "In16.Cu" signal "GND7")
		(2 "B.Cu" signal "BOTTOM")
		(9 "F.Adhes" user "F.Adhesive")
		(11 "B.Adhes" user "B.Adhesive")
		(13 "F.Paste" user "Package Geometry/Pastemask Top")
		(15 "B.Paste" user "Package Geometry/Pastemask Bottom")
		(5 "F.SilkS" user "Ref Des/Silkscreen Top")
		(7 "B.SilkS" user "Ref Des/Silkscreen Bottom")
		(1 "F.Mask" user "Board Geometry/Soldermask Top")
		(3 "B.Mask" user "Board Geometry/Soldermask Bottom")
		(17 "Dwgs.User" user "User.Drawings")
		(19 "Cmts.User" user "User.Comments")
		(21 "Eco1.User" user "User.Eco1")
		(23 "Eco2.User" user "User.Eco2")
		(25 "Edge.Cuts" user "Board Geometry/Outline")
		(27 "Margin" user)
		(31 "F.CrtYd" user "Package Geometry/Place Bound Top")
		(29 "B.CrtYd" user "Package Geometry/Place Bound Bottom")
		(35 "F.Fab" user "Ref Des/Assembly Top")
		(33 "B.Fab" user "Ref Des/Assembly Bottom")
	)
	(footprint ""
		(layer "B.Cu")
		(at 411.675326 -110.497366 180)
		(property "Reference" "R391"
			(at 0 0 0)
			(layer "B.SilkS")
			(hide yes)
			(effects
				(font
					(size 1.27 1.27)
				)
				(justify mirror)
			)
		)
		(property "Value" ""
			(at 0 0 0)
			(layer "B.Fab")
			(effects
				(font
					(size 1.27 1.27)
				)
				(justify mirror)
			)
		)
		(duplicate_pad_numbers_are_jumpers no)
		(fp_line
			(start 0.7874 0.4064)
			(end 0.7874 -0.4064)
			(stroke
				(width 0.1524)
				(type default)
			)
			(layer "B.SilkS")
		)
		(fp_line
			(start 0.7874 -0.4064)
			(end -0.7874 -0.4064)
			(stroke
				(width 0.1524)
				(type default)
			)
			(layer "B.SilkS")
		)
		(fp_line
			(start -0.7874 0.4064)
			(end 0.7874 0.4064)
			(stroke
				(width 0.1524)
				(type default)
			)
			(layer "B.SilkS")
		)
		(fp_line
			(start -0.7874 -0.4064)
			(end -0.7874 0.4064)
			(stroke
				(width 0.1524)
				(type default)
			)
			(layer "B.SilkS")
		)
		(fp_line
			(start 0.67945 0.3048)
			(end 0.67945 -0.305054)
			(stroke
				(width 0.1)
				(type default)
			)
			(layer "B.Fab")
		)
		(fp_line
			(start 0.67945 -0.305054)
			(end 0.12065 -0.305054)
			(stroke
				(width 0.1)
				(type default)
			)
			(layer "B.Fab")
		)
		(fp_line
			(start 0.12065 0.3048)
			(end 0.67945 0.3048)
			(stroke
				(width 0.1)
				(type default)
			)
			(layer "B.Fab")
		)
		(fp_line
			(start 0.12065 0.2794)
			(end 0.12065 0.3048)
			(stroke
				(width 0.1)
				(type default)
			)
			(layer "B.Fab")
		)
		(fp_line
			(start 0.12065 -0.2794)
			(end -0.12065 -0.2794)
			(stroke
				(width 0.1)
				(type default)
			)
			(layer "B.Fab")
		)
		(fp_line
			(start 0.12065 -0.305054)
			(end 0.12065 -0.2794)
			(stroke
				(width 0.1)
				(type default)
			)
			(layer "B.Fab")
		)
		(fp_line
			(start -0.120396 0.3048)
			(end -0.120396 0.2794)
			(stroke
				(width 0.1)
				(type default)
			)
			(layer "B.Fab")
		)
		(fp_line
			(start -0.120396 0.2794)
			(end 0.12065 0.2794)
			(stroke
				(width 0.1)
				(type default)
			)
			(layer "B.Fab")
		)
		(fp_line
			(start -0.12065 -0.2794)
			(end -0.12065 -0.3048)
			(stroke
				(width 0.1)
				(type default)
			)
			(layer "B.Fab")
		)
		(fp_line
			(start -0.12065 -0.3048)
			(end -0.67945 -0.3048)
			(stroke
				(width 0.1)
				(type default)
			)
			(layer "B.Fab")
		)
		(fp_line
			(start -0.67945 0.3048)
			(end -0.120396 0.3048)
			(stroke
				(width 0.1)
				(type default)
			)
			(layer "B.Fab")
		)
		(fp_line
			(start -0.67945 -0.3048)
			(end -0.67945 0.3048)
			(stroke
				(width 0.1)
				(type default)
			)
			(layer "B.Fab")
		)
		(pad "1" smd circle
			(at 0.40005 0)
			(size 0 0)
			(layers "B.Cu" "B.Mask" "B.Paste")
			(net "NIC7_BIF2_N")
		)
		(pad "2" smd circle
			(at -0.40005 0)
			(size 0 0)
			(layers "B.Cu" "B.Mask" "B.Paste")
			(net "GND")
		)
	)
	(footprint ""
		(layer "B.Cu")
		(at 71.049896 -293.52494 180)
		(property "Reference" "C2929"
			(at 0 0 0)
			(layer "B.SilkS")
			(hide yes)
			(effects
				(font
					(size 1.27 1.27)
				)
				(justify mirror)
			)
		)
		(property "Value" ""
			(at 0 0 0)
			(layer "B.Fab")
			(effects
				(font
					(size 1.27 1.27)
				)
				(justify mirror)
			)
		)
		(duplicate_pad_numbers_are_jumpers no)
		(fp_line
			(start 0.299974 0.150114)
			(end 0.299974 -0.150114)
			(stroke
				(width 0.1)
				(type default)
			)
			(layer "B.Fab")
		)
		(fp_line
			(start 0.299974 -0.150114)
			(end -0.299974 -0.150114)
			(stroke
				(width 0.1)
				(type default)
			)
			(layer "B.Fab")
		)
		(fp_line
			(start -0.299974 0.150114)
			(end 0.299974 0.150114)
			(stroke
				(width 0.1)
				(type default)
			)
			(layer "B.Fab")
		)
		(fp_line
			(start -0.299974 -0.150114)
			(end -0.299974 0.150114)
			(stroke
				(width 0.1)
				(type default)
			)
			(layer "B.Fab")
		)
		(pad "1" smd rect
			(at 0.2667 0)
			(size 0.3048 0.381)
			(layers "B.Cu" "B.Mask" "B.Paste")
			(net "P1V25_PEX0")
		)
		(pad "2" smd rect
			(at -0.2667 0)
			(size 0.3048 0.381)
			(layers "B.Cu" "B.Mask" "B.Paste")
			(net "GND")
		)
	)
	(footprint ""
		(layer "B.Cu")
		(at 124.217938 -308.580028 90)
		(property "Reference" "C4246"
			(at 0 0 90)
			(layer "B.SilkS")
			(hide yes)
			(effects
				(font
					(size 1.27 1.27)
				)
				(justify mirror)
			)
		)
		(property "Value" ""
			(at 0 0 90)
			(layer "B.Fab")
			(effects
				(font
					(size 1.27 1.27)
				)
				(justify mirror)
			)
		)
		(duplicate_pad_numbers_are_jumpers no)
		(fp_line
			(start 1.2954 -0.5842)
			(end -1.2954 -0.5842)
			(stroke
				(width 0.1524)
				(type default)
			)
			(layer "B.SilkS")
		)
		(fp_line
			(start -1.2954 -0.5842)
			(end -1.2954 0.5842)
			(stroke
				(width 0.1524)
				(type default)
			)
			(layer "B.SilkS")
		)
		(fp_line
			(start 1.2954 0.5842)
			(end 1.2954 -0.5842)
			(stroke
				(width 0.1524)
				(type default)
			)
			(layer "B.SilkS")
		)
		(fp_line
			(start -1.2954 0.5842)
			(end 1.2954 0.5842)
			(stroke
				(width 0.1524)
				(type default)
			)
			(layer "B.SilkS")
		)
		(fp_line
			(start 0.8636 -0.4572)
			(end -0.8636 -0.4572)
			(stroke
				(width 0.1)
				(type default)
			)
			(layer "B.Fab")
		)
		(fp_line
			(start -0.8636 -0.4572)
			(end -0.8636 -0.4064)
			(stroke
				(width 0.1)
				(type default)
			)
			(layer "B.Fab")
		)
		(fp_line
			(start 1.1938 -0.4064)
			(end 0.8636 -0.4064)
			(stroke
				(width 0.1)
				(type default)
			)
			(layer "B.Fab")
		)
		(fp_line
			(start 0.8636 -0.4064)
			(end 0.8636 -0.4572)
			(stroke
				(width 0.1)
				(type default)
			)
			(layer "B.Fab")
		)
		(fp_line
			(start -0.8636 -0.4064)
			(end -1.1938 -0.4064)
			(stroke
				(width 0.1)
				(type default)
			)
			(layer "B.Fab")
		)
		(fp_line
			(start -1.1938 -0.4064)
			(end -1.1938 0.4064)
			(stroke
				(width 0.1)
				(type default)
			)
			(layer "B.Fab")
		)
		(fp_line
			(start 1.1938 0.4064)
			(end 1.1938 -0.4064)
			(stroke
				(width 0.1)
				(type default)
			)
			(layer "B.Fab")
		)
		(fp_line
			(start 0.8636 0.4064)
			(end 1.1938 0.4064)
			(stroke
				(width 0.1)
				(type default)
			)
			(layer "B.Fab")
		)
		(fp_line
			(start -0.8636 0.4064)
			(end -0.8636 0.4572)
			(stroke
				(width 0.1)
				(type default)
			)
			(layer "B.Fab")
		)
		(fp_line
			(start -1.1938 0.4064)
			(end -0.8636 0.4064)
			(stroke
				(width 0.1)
				(type default)
			)
			(layer "B.Fab")
		)
		(fp_line
			(start 0.8636 0.4572)
			(end 0.8636 0.4064)
			(stroke
				(width 0.1)
				(type default)
			)
			(layer "B.Fab")
		)
		(fp_line
			(start -0.8636 0.4572)
			(end 0.8636 0.4572)
			(stroke
				(width 0.1)
				(type default)
			)
			(layer "B.Fab")
		)
		(pad "1" smd rect
			(at 0.7366 0)
			(size 0.7112 0.8128)
			(layers "B.Cu" "B.Mask" "B.Paste")
			(net "P0V8_PEX1")
		)
		(pad "2" smd rect
			(at -0.7366 0)
			(size 0.7112 0.8128)
			(layers "B.Cu" "B.Mask" "B.Paste")
			(net "GND")
		)
	)
	(footprint ""
		(layer "B.Cu")
		(at 101.223318 -391.3378 180)
		(property "Reference" "C3627"
			(at 0 0 0)
			(layer "B.SilkS")
			(hide yes)
			(effects
				(font
					(size 1.27 1.27)
				)
				(justify mirror)
			)
		)
		(property "Value" ""
			(at 0 0 0)
			(layer "B.Fab")
			(effects
				(font
					(size 1.27 1.27)
				)
				(justify mirror)
			)
		)
		(duplicate_pad_numbers_are_jumpers no)
		(fp_line
			(start 0.7874 0.4064)
			(end 0.7874 -0.4064)
			(stroke
				(width 0.1524)
				(type default)
			)
			(layer "B.SilkS")
		)
		(fp_line
			(start 0.7874 -0.4064)
			(end -0.7874 -0.4064)
			(stroke
				(width 0.1524)
				(type default)
			)
			(layer "B.SilkS")
		)
		(fp_line
			(start -0.7874 0.4064)
			(end 0.7874 0.4064)
			(stroke
				(width 0.1524)
				(type default)
			)
			(layer "B.SilkS")
		)
		(fp_line
			(start -0.7874 -0.4064)
			(end -0.7874 0.4064)
			(stroke
				(width 0.1524)
				(type default)
			)
			(layer "B.SilkS")
		)
		(fp_line
			(start 0.67945 0.3048)
			(end 0.67945 -0.305054)
			(stroke
				(width 0.1)
				(type default)
			)
			(layer "B.Fab")
		)
		(fp_line
			(start 0.67945 -0.305054)
			(end 0.12065 -0.305054)
			(stroke
				(width 0.1)
				(type default)
			)
			(layer "B.Fab")
		)
		(fp_line
			(start 0.12065 0.3048)
			(end 0.67945 0.3048)
			(stroke
				(width 0.1)
				(type default)
			)
			(layer "B.Fab")
		)
		(fp_line
			(start 0.12065 0.2794)
			(end 0.12065 0.3048)
			(stroke
				(width 0.1)
				(type default)
			)
			(layer "B.Fab")
		)
		(fp_line
			(start 0.12065 -0.2794)
			(end -0.12065 -0.2794)
			(stroke
				(width 0.1)
				(type default)
			)
			(layer "B.Fab")
		)
		(fp_line
			(start 0.12065 -0.305054)
			(end 0.12065 -0.2794)
			(stroke
				(width 0.1)
				(type default)
			)
			(layer "B.Fab")
		)
		(fp_line
			(start -0.120396 0.3048)
			(end -0.120396 0.2794)
			(stroke
				(width 0.1)
				(type default)
			)
			(layer "B.Fab")
		)
		(fp_line
			(start -0.120396 0.2794)
			(end 0.12065 0.2794)
			(stroke
				(width 0.1)
				(type default)
			)
			(layer "B.Fab")
		)
		(fp_line
			(start -0.12065 -0.2794)
			(end -0.12065 -0.3048)
			(stroke
				(width 0.1)
				(type default)
			)
			(layer "B.Fab")
		)
		(fp_line
			(start -0.12065 -0.3048)
			(end -0.67945 -0.3048)
			(stroke
				(width 0.1)
				(type default)
			)
			(layer "B.Fab")
		)
		(fp_line
			(start -0.67945 0.3048)
			(end -0.120396 0.3048)
			(stroke
				(width 0.1)
				(type default)
			)
			(layer "B.Fab")
		)
		(fp_line
			(start -0.67945 -0.3048)
			(end -0.67945 0.3048)
			(stroke
				(width 0.1)
				(type default)
			)
			(layer "B.Fab")
		)
		(pad "1" smd circle
			(at 0.40005 0)
			(size 0 0)
			(layers "B.Cu" "B.Mask" "B.Paste")
			(net "P3V3_BIC_USB_HUB")
		)
		(pad "2" smd circle
			(at -0.40005 0)
			(size 0 0)
			(layers "B.Cu" "B.Mask" "B.Paste")
			(net "GND")
		)
	)
	(footprint ""
		(layer "B.Cu")
		(at 176.224946 -297.79976 90)
		(property "Reference" "C1405"
			(at 0 0 90)
			(layer "B.SilkS")
			(hide yes)
			(effects
				(font
					(size 1.27 1.27)
				)
				(justify mirror)
			)
		)
		(property "Value" ""
			(at 0 0 90)
			(layer "B.Fab")
			(effects
				(font
					(size 1.27 1.27)
				)
				(justify mirror)
			)
		)
		(duplicate_pad_numbers_are_jumpers no)
		(fp_line
			(start 0.299974 -0.150114)
			(end -0.299974 -0.150114)
			(stroke
				(width 0.1)
				(type default)
			)
			(layer "B.Fab")
		)
		(fp_line
			(start -0.299974 -0.150114)
			(end -0.299974 0.150114)
			(stroke
				(width 0.1)
				(type default)
			)
			(layer "B.Fab")
		)
		(fp_line
			(start 0.299974 0.150114)
			(end 0.299974 -0.150114)
			(stroke
				(width 0.1)
				(type default)
			)
			(layer "B.Fab")
		)
		(fp_line
			(start -0.299974 0.150114)
			(end 0.299974 0.150114)
			(stroke
				(width 0.1)
				(type default)
			)
			(layer "B.Fab")
		)
		(pad "1" smd rect
			(at 0.2667 0 270)
			(size 0.3048 0.381)
			(layers "B.Cu" "B.Mask" "B.Paste")
			(net "P0V8_PEX1")
		)
		(pad "2" smd rect
			(at -0.2667 0 270)
			(size 0.3048 0.381)
			(layers "B.Cu" "B.Mask" "B.Paste")
			(net "GND")
		)
	)
	(footprint ""
		(layer "B.Cu")
		(at 104.845866 -347.125036 90)
		(property "Reference" "C4183"
			(at 0 0 90)
			(layer "B.SilkS")
			(hide yes)
			(effects
				(font
					(size 1.27 1.27)
				)
				(justify mirror)
			)
		)
		(property "Value" ""
			(at 0 0 90)
			(layer "B.Fab")
			(effects
				(font
					(size 1.27 1.27)
				)
				(justify mirror)
			)
		)
		(duplicate_pad_numbers_are_jumpers no)
		(fp_line
			(start 0.7874 -0.4064)
			(end -0.7874 -0.4064)
			(stroke
				(width 0.1524)
				(type default)
			)
			(layer "B.SilkS")
		)
		(fp_line
			(start -0.7874 -0.4064)
			(end -0.7874 0.4064)
			(stroke
				(width 0.1524)
				(type default)
			)
			(layer "B.SilkS")
		)
		(fp_line
			(start 0.7874 0.4064)
			(end 0.7874 -0.4064)
			(stroke
				(width 0.1524)
				(type default)
			)
			(layer "B.SilkS")
		)
		(fp_line
			(start -0.7874 0.4064)
			(end 0.7874 0.4064)
			(stroke
				(width 0.1524)
				(type default)
			)
			(layer "B.SilkS")
		)
		(fp_line
			(start 0.67945 -0.305054)
			(end 0.12065 -0.305054)
			(stroke
				(width 0.1)
				(type default)
			)
			(layer "B.Fab")
		)
		(fp_line
			(start 0.12065 -0.305054)
			(end 0.12065 -0.2794)
			(stroke
				(width 0.1)
				(type default)
			)
			(layer "B.Fab")
		)
		(fp_line
			(start -0.12065 -0.3048)
			(end -0.67945 -0.3048)
			(stroke
				(width 0.1)
				(type default)
			)
			(layer "B.Fab")
		)
		(fp_line
			(start -0.67945 -0.3048)
			(end -0.67945 0.3048)
			(stroke
				(width 0.1)
				(type default)
			)
			(layer "B.Fab")
		)
		(fp_line
			(start 0.12065 -0.2794)
			(end -0.12065 -0.2794)
			(stroke
				(width 0.1)
				(type default)
			)
			(layer "B.Fab")
		)
		(fp_line
			(start -0.12065 -0.2794)
			(end -0.12065 -0.3048)
			(stroke
				(width 0.1)
				(type default)
			)
			(layer "B.Fab")
		)
		(fp_line
			(start 0.12065 0.2794)
			(end 0.12065 0.3048)
			(stroke
				(width 0.1)
				(type default)
			)
			(layer "B.Fab")
		)
		(fp_line
			(start -0.120396 0.2794)
			(end 0.12065 0.2794)
			(stroke
				(width 0.1)
				(type default)
			)
			(layer "B.Fab")
		)
		(fp_line
			(start 0.67945 0.3048)
			(end 0.67945 -0.305054)
			(stroke
				(width 0.1)
				(type default)
			)
			(layer "B.Fab")
		)
		(fp_line
			(start 0.12065 0.3048)
			(end 0.67945 0.3048)
			(stroke
				(width 0.1)
				(type default)
			)
			(layer "B.Fab")
		)
		(fp_line
			(start -0.120396 0.3048)
			(end -0.120396 0.2794)
			(stroke
				(width 0.1)
				(type default)
			)
			(layer "B.Fab")
		)
		(fp_line
			(start -0.67945 0.3048)
			(end -0.120396 0.3048)
			(stroke
				(width 0.1)
				(type default)
			)
			(layer "B.Fab")
		)
		(pad "1" smd circle
			(at 0.40005 0 270)
			(size 0 0)
			(layers "B.Cu" "B.Mask" "B.Paste")
			(net "P3V3_CLK_BUFFER_9ZXL0451E_S3_VZX3P3A")
		)
		(pad "2" smd circle
			(at -0.40005 0 270)
			(size 0 0)
			(layers "B.Cu" "B.Mask" "B.Paste")
			(net "GND")
		)
	)
	(footprint ""
		(layer "B.Cu")
		(at 131.51485 -171.43857 90)
		(property "Reference" "R1468"
			(at 0 0 90)
			(layer "B.SilkS")
			(hide yes)
			(effects
				(font
					(size 1.27 1.27)
				)
				(justify mirror)
			)
		)
		(property "Value" ""
			(at 0 0 90)
			(layer "B.Fab")
			(effects
				(font
					(size 1.27 1.27)
				)
				(justify mirror)
			)
		)
		(duplicate_pad_numbers_are_jumpers no)
		(fp_line
			(start 0.7874 -0.4064)
			(end -0.7874 -0.4064)
			(stroke
				(width 0.1524)
				(type default)
			)
			(layer "B.SilkS")
		)
		(fp_line
			(start -0.7874 -0.4064)
			(end -0.7874 0.4064)
			(stroke
				(width 0.1524)
				(type default)
			)
			(layer "B.SilkS")
		)
		(fp_line
			(start 0.7874 0.4064)
			(end 0.7874 -0.4064)
			(stroke
				(width 0.1524)
				(type default)
			)
			(layer "B.SilkS")
		)
		(fp_line
			(start -0.7874 0.4064)
			(end 0.7874 0.4064)
			(stroke
				(width 0.1524)
				(type default)
			)
			(layer "B.SilkS")
		)
		(fp_line
			(start 0.67945 -0.305054)
			(end 0.12065 -0.305054)
			(stroke
				(width 0.1)
				(type default)
			)
			(layer "B.Fab")
		)
		(fp_line
			(start 0.12065 -0.305054)
			(end 0.12065 -0.2794)
			(stroke
				(width 0.1)
				(type default)
			)
			(layer "B.Fab")
		)
		(fp_line
			(start -0.12065 -0.3048)
			(end -0.67945 -0.3048)
			(stroke
				(width 0.1)
				(type default)
			)
			(layer "B.Fab")
		)
		(fp_line
			(start -0.67945 -0.3048)
			(end -0.67945 0.3048)
			(stroke
				(width 0.1)
				(type default)
			)
			(layer "B.Fab")
		)
		(fp_line
			(start 0.12065 -0.2794)
			(end -0.12065 -0.2794)
			(stroke
				(width 0.1)
				(type default)
			)
			(layer "B.Fab")
		)
		(fp_line
			(start -0.12065 -0.2794)
			(end -0.12065 -0.3048)
			(stroke
				(width 0.1)
				(type default)
			)
			(layer "B.Fab")
		)
		(fp_line
			(start 0.12065 0.2794)
			(end 0.12065 0.3048)
			(stroke
				(width 0.1)
				(type default)
			)
			(layer "B.Fab")
		)
		(fp_line
			(start -0.120396 0.2794)
			(end 0.12065 0.2794)
			(stroke
				(width 0.1)
				(type default)
			)
			(layer "B.Fab")
		)
		(fp_line
			(start 0.67945 0.3048)
			(end 0.67945 -0.305054)
			(stroke
				(width 0.1)
				(type default)
			)
			(layer "B.Fab")
		)
		(fp_line
			(start 0.12065 0.3048)
			(end 0.67945 0.3048)
			(stroke
				(width 0.1)
				(type default)
			)
			(layer "B.Fab")
		)
		(fp_line
			(start -0.120396 0.3048)
			(end -0.120396 0.2794)
			(stroke
				(width 0.1)
				(type default)
			)
			(layer "B.Fab")
		)
		(fp_line
			(start -0.67945 0.3048)
			(end -0.120396 0.3048)
			(stroke
				(width 0.1)
				(type default)
			)
			(layer "B.Fab")
		)
		(pad "1" smd circle
			(at 0.40005 0 270)
			(size 0 0)
			(layers "B.Cu" "B.Mask" "B.Paste")
			(net "SMB_BMC_9QXL2001_SCL")
		)
		(pad "2" smd circle
			(at -0.40005 0 270)
			(size 0 0)
			(layers "B.Cu" "B.Mask" "B.Paste")
			(net "SMB_CLK_ISO_R_SCL")
		)
	)
)
